# S9S_MB_2U (Grand Teton) — schematic netlist excerpt (pin names and nets, part order shuffled) for the footprints in the layout excerpt that follows; sources: Cadence DE-HDL packaged netlist, KiCad conversion of 03242023_DA0F0TMBIJ0_F0T_Motherboard_J_brd_V01_OCP.brd

PL23  Q_INDUCTOR  100NH/16A IND  pkg SMLF  page 293 : \1\ = P12V_AUX ; \2\ = SW_P12V_PVCCINFAON_CPU1_FLT
R4666  Q_RES  0 5% EMPTY  pkg 0402LF  page 167 : A = P2E_MB_BMC_RX_DN<0> ; B = P2E_MB_BMC_RX_R2_DN<0>
PC1644  Q_CAPP  560UF 2.5V 20% OSCON  pkg THLF  page 279 : A = PVCCD_HV_CPU0 ; B = GND

(kicad_pcb
	(version 20260206)
	(generator "pcbnew")
	(generator_version "10.0")
	(general
		(thickness 1.6)
		(legacy_teardrops no)
	)
	(paper "A4")
	(title_block
		(title "03242023_DA0F0TMBIJ0_F0T_Motherboard_J_brd_V01_OCP.brd")
		(comment 1 "Grand Teton / footprints 827-829 of 6105")
	)
	(layers
		(0 "F.Cu" signal "TOP")
		(4 "In1.Cu" signal "GND")
		(6 "In2.Cu" signal "IN1")
		(8 "In3.Cu" signal "GND1")
		(10 "In4.Cu" signal "IN2")
		(12 "In5.Cu" signal "GND2")
		(14 "In6.Cu" signal "IN3")
		(16 "In7.Cu" signal "GND3")
		(18 "In8.Cu" signal "VCC")
		(20 "In9.Cu" signal "VCC1")
		(22 "In10.Cu" signal "GND4")
		(24 "In11.Cu" signal "IN4")
		(26 "In12.Cu" signal "GND5")
		(28 "In13.Cu" signal "IN5")
		(30 "In14.Cu" signal "GND6")
		(32 "In15.Cu" signal "IN6")
		(34 "In16.Cu" signal "GND7")
		(2 "B.Cu" signal "BOTTOM")
		(9 "F.Adhes" user "F.Adhesive")
		(11 "B.Adhes" user "B.Adhesive")
		(13 "F.Paste" user "Package Geometry/Pastemask Top")
		(15 "B.Paste" user "Package Geometry/Pastemask Bottom")
		(5 "F.SilkS" user "Ref Des/Silkscreen Top")
		(7 "B.SilkS" user "Ref Des/Silkscreen Bottom")
		(1 "F.Mask" user "Board Geometry/Soldermask Top")
		(3 "B.Mask" user "Board Geometry/Soldermask Bottom")
		(17 "Dwgs.User" user "User.Drawings")
		(19 "Cmts.User" user "User.Comments")
		(21 "Eco1.User" user "User.Eco1")
		(23 "Eco2.User" user "User.Eco2")
		(25 "Edge.Cuts" user "Board Geometry/Outline")
		(27 "Margin" user)
		(31 "F.CrtYd" user "Package Geometry/Place Bound Top")
		(29 "B.CrtYd" user "Package Geometry/Place Bound Bottom")
		(35 "F.Fab" user "Ref Des/Assembly Top")
		(33 "B.Fab" user "Ref Des/Assembly Bottom")
	)
	(footprint ""
		(layer "F.Cu")
		(at 45.805344 -148.837396 90)
		(property "Reference" "PL23"
			(at 0.094742 -5.884164 0)
			(unlocked yes)
			(layer "F.SilkS")
			(effects
				(font
					(size 0.7874 0.5842)
					(thickness 0.1524)
				)
				(justify left)
			)
		)
		(property "Value" ""
			(at 0 0 90)
			(layer "F.Fab")
			(effects
				(font
					(size 1.27 1.27)
				)
			)
		)
		(duplicate_pad_numbers_are_jumpers no)
		(fp_line
			(start 2.249932 -2.249932)
			(end 2.249932 -1.3843)
			(stroke
				(width 0.1524)
				(type default)
			)
			(layer "F.SilkS")
		)
		(fp_line
			(start -2.249932 -2.249932)
			(end 2.249932 -2.249932)
			(stroke
				(width 0.1524)
				(type default)
			)
			(layer "F.SilkS")
		)
		(fp_line
			(start -2.249932 -1.3843)
			(end -2.249932 -2.249932)
			(stroke
				(width 0.1524)
				(type default)
			)
			(layer "F.SilkS")
		)
		(fp_line
			(start 2.249932 1.3843)
			(end 2.249932 2.249932)
			(stroke
				(width 0.1524)
				(type default)
			)
			(layer "F.SilkS")
		)
		(fp_line
			(start 2.249932 2.249932)
			(end -2.249932 2.249932)
			(stroke
				(width 0.1524)
				(type default)
			)
			(layer "F.SilkS")
		)
		(fp_line
			(start -2.249932 2.249932)
			(end -2.249932 1.3843)
			(stroke
				(width 0.1524)
				(type default)
			)
			(layer "F.SilkS")
		)
		(fp_line
			(start 2.249932 -2.249932)
			(end 2.249932 2.249932)
			(stroke
				(width 0.1)
				(type default)
			)
			(layer "F.Fab")
		)
		(fp_line
			(start -2.249932 -2.249932)
			(end 2.249932 -2.249932)
			(stroke
				(width 0.1)
				(type default)
			)
			(layer "F.Fab")
		)
		(fp_line
			(start 2.249932 2.249932)
			(end -2.249932 2.249932)
			(stroke
				(width 0.1)
				(type default)
			)
			(layer "F.Fab")
		)
		(fp_line
			(start -2.249932 2.249932)
			(end -2.249932 -2.249932)
			(stroke
				(width 0.1)
				(type default)
			)
			(layer "F.Fab")
		)
		(pad "1" smd rect
			(at -1.82499 0 90)
			(size 1.0668 2.5146)
			(layers "F.Cu" "F.Mask" "F.Paste")
			(net "P12V_AUX")
		)
		(pad "2" smd rect
			(at 1.82499 0 90)
			(size 1.0668 2.5146)
			(layers "F.Cu" "F.Mask" "F.Paste")
			(net "SW_P12V_PVCCINFAON_CPU1_FLT")
		)
	)
	(footprint ""
		(layer "F.Cu")
		(at 24.684482 -397.687292 90)
		(property "Reference" "R4666"
			(at 0 0 90)
			(layer "F.SilkS")
			(hide yes)
			(effects
				(font
					(size 1.27 1.27)
				)
			)
		)
		(property "Value" ""
			(at 0 0 90)
			(layer "F.Fab")
			(effects
				(font
					(size 1.27 1.27)
				)
			)
		)
		(duplicate_pad_numbers_are_jumpers no)
		(fp_line
			(start -0.7874 -0.4064)
			(end 0.7874 -0.4064)
			(stroke
				(width 0.1524)
				(type default)
			)
			(layer "F.SilkS")
		)
		(fp_line
			(start 0.7874 0.4064)
			(end -0.002032 0.4064)
			(stroke
				(width 0.1524)
				(type default)
			)
			(layer "F.SilkS")
		)
		(fp_line
			(start -0.7874 0.4064)
			(end -0.7874 -0.4064)
			(stroke
				(width 0.1524)
				(type default)
			)
			(layer "F.SilkS")
		)
		(fp_line
			(start -0.12065 -0.305054)
			(end -0.12065 -0.2794)
			(stroke
				(width 0.1)
				(type default)
			)
			(layer "F.Fab")
		)
		(fp_line
			(start -0.67945 -0.305054)
			(end -0.12065 -0.305054)
			(stroke
				(width 0.1)
				(type default)
			)
			(layer "F.Fab")
		)
		(fp_line
			(start 0.67945 -0.3048)
			(end 0.67945 0.3048)
			(stroke
				(width 0.1)
				(type default)
			)
			(layer "F.Fab")
		)
		(fp_line
			(start 0.12065 -0.3048)
			(end 0.67945 -0.3048)
			(stroke
				(width 0.1)
				(type default)
			)
			(layer "F.Fab")
		)
		(fp_line
			(start 0.12065 -0.2794)
			(end 0.12065 -0.3048)
			(stroke
				(width 0.1)
				(type default)
			)
			(layer "F.Fab")
		)
		(fp_line
			(start -0.12065 -0.2794)
			(end 0.12065 -0.2794)
			(stroke
				(width 0.1)
				(type default)
			)
			(layer "F.Fab")
		)
		(fp_line
			(start 0.120396 0.2794)
			(end -0.12065 0.2794)
			(stroke
				(width 0.1)
				(type default)
			)
			(layer "F.Fab")
		)
		(fp_line
			(start -0.12065 0.2794)
			(end -0.12065 0.3048)
			(stroke
				(width 0.1)
				(type default)
			)
			(layer "F.Fab")
		)
		(fp_line
			(start 0.67945 0.3048)
			(end 0.120396 0.3048)
			(stroke
				(width 0.1)
				(type default)
			)
			(layer "F.Fab")
		)
		(fp_line
			(start 0.120396 0.3048)
			(end 0.120396 0.2794)
			(stroke
				(width 0.1)
				(type default)
			)
			(layer "F.Fab")
		)
		(fp_line
			(start -0.12065 0.3048)
			(end -0.67945 0.3048)
			(stroke
				(width 0.1)
				(type default)
			)
			(layer "F.Fab")
		)
		(fp_line
			(start -0.67945 0.3048)
			(end -0.67945 -0.305054)
			(stroke
				(width 0.1)
				(type default)
			)
			(layer "F.Fab")
		)
		(pad "1" smd rect
			(at -0.40005 0 270)
			(size 0.4572 0.508)
			(layers "F.Cu" "F.Mask" "F.Paste")
			(net "P2E_MB_BMC_RX_DN<0>")
		)
		(pad "2" smd rect
			(at 0.40005 0 270)
			(size 0.4572 0.508)
			(layers "F.Cu" "F.Mask" "F.Paste")
			(net "P2E_MB_BMC_RX_R2_DN<0>")
		)
	)
	(footprint ""
		(layer "F.Cu")
		(at 400.558 -158.562548)
		(property "Reference" "PC1644"
			(at 0 0 0)
			(layer "F.SilkS")
			(hide yes)
			(effects
				(font
					(size 1.27 1.27)
				)
			)
		)
		(property "Value" ""
			(at 0 0 0)
			(layer "F.Fab")
			(effects
				(font
					(size 1.27 1.27)
				)
			)
		)
		(duplicate_pad_numbers_are_jumpers no)
		(fp_line
			(start 2.750058 0.999998)
			(end -2.750058 0.999998)
			(stroke
				(width 0.1524)
				(type default)
			)
			(layer "F.SilkS")
		)
		(fp_circle
			(center 0 0.999998)
			(end 2.750058 0.999998)
			(stroke
				(width 0.1524)
				(type default)
			)
			(fill no)
			(layer "F.SilkS")
		)
		(fp_poly
			(pts
				(arc
					(start 2.750058 0.999998)
					(mid 0 3.750056)
					(end -2.750058 0.999998)
				)
			)
			(stroke
				(width 0)
				(type default)
			)
			(fill yes)
			(layer "F.SilkS")
		)
		(fp_circle
			(center 0 0.999998)
			(end 2.750058 0.999998)
			(stroke
				(width 0.1)
				(type default)
			)
			(fill no)
			(layer "F.Fab")
		)
		(pad "1" thru_hole rect
			(at 0 0)
			(size 1.5748 1.5748)
			(drill 1.0668)
			(layers "*.Cu" "*.Mask")
			(remove_unused_layers no)
			(net "PVCCD_HV_CPU0")
			(clearance 0)
			(padstack
				(mode front_inner_back)
				(layer "Inner"
					(shape circle)
					(size 1.5748 1.5748)
					(clearance 0)
				)
				(layer "B.Cu"
					(shape rect)
					(size 1.5748 1.5748)
					(clearance 0)
				)
			)
		)
		(pad "2" thru_hole circle
			(at 0 1.999996)
			(size 1.5748 1.5748)
			(drill 1.0668)
			(layers "*.Cu" "*.Mask")
			(remove_unused_layers no)
			(net "GND")
			(clearance 0)
		)
	)
)
